FILE_TYPE = CONNECTIVITY;
{Allegro Design Entry HDL 17.2-2016 S081 (4005846) 1/11/2022}
"PAGE_NUMBER" = 279;
0"NC";
1"PVCCFA_EHV_CPU1_PVCC";
2"PVCCFA_EHV_CPU1_PVCC";
3"SW_P12V_PVCCINFAON_CPU1_FLT\g";
4"SW_P12V_PVCCINFAON_CPU1_FLT\g";
5"PVCCINFAON_CPU1\g";
6"PVCCINFAON_CPU1\g";
7"PVCCINFAON_CPU1\g";
8"PVCCINFAON_CPU1\g";
9"P12V_AUX\g";
10"SW_P12V_PVCCINFAON_CPU1_FLT\g";
11"GND\g";
12"GND\g";
13"GND\g";
14"GND\g";
15"GND\g";
16"GND\g";
17"GND\g";
18"GND\g";
19"GND\g";
20"GND\g";
21"GND\g";
22"GND\g";
23"GND\g";
24"GND\g";
25"GND\g";
26"GND\g";
27"GND\g";
28"GND\g";
29"SW_PVCCINFAON_CPU1_BOOT1_R";
30"SW_PVCCINFAON_CPU1_BOOT2_R";
31"SW_PVCCINFAON_CPU1_SW1";
32"PVCCINFAON_CPU1_VOS1";
33"SW_PVCCINFAON_CPU1_SW2";
34"SW_PVCCINFAON_CPU1_BOOTR2"CDS_PHYS_NET_NAME"SW_PVCCINFAON_CPU1_BOOTR2";
35"SW_PVCCINFAON_CPU1_BOOTR1"CDS_PHYS_NET_NAME"SW_PVCCINFAON_CPU1_BOOTR1";
36"SW_PVCCINFAON_CPU1_BOOT1"CDS_PHYS_NET_NAME"SW_PVCCINFAON_CPU1_BOOT1";
37"PVCCINFAON_CPU1_VDD1";
38"SW_PVCCINFAON_CPU1_BOOT2"CDS_PHYS_NET_NAME"SW_PVCCINFAON_CPU1_BOOT2";
39"PVCCINFAON_CPU1_VDD2";
40"PVCCINFAON_CPU1_VOS2";
41"PVCCINFAON_CPU1_APWM2";
42"PVCCINFAON_CPU1_ACSP1";
43"PVCCINFAON_CPU1_VREF"CDS_PHYS_NET_NAME"PVCCINFAON_CPU1_VREF";
44"PVCCINFAON_CPU1_ATSEN";
45"PVCCINFAON_CPU1_APWM1";
46"PVCCINFAON_CPU1_ACSP2";
47"PVCCINFAON_CPU1_VREF"CDS_PHYS_NET_NAME"PVCCINFAON_CPU1_VREF";
48"PVCCINFAON_CPU1_ATSEN";
49"PVCCINFAON_CPU1_LSET1";
50"PVCCINFAON_CPU1_LSET2";
%"UNIVERSAL_GND"
"1","(-9000,7625)","0","logical_power","I1";
;
HDL_POWER"GND"
CDS_LIB"logical_power";
"A"11;
%"Q_CAP"
"1","(-8500,8875)","0","pure_quanta","I10";
;
PART_NUMBER"CH5222KEB01"
MATERIAL"X6S"
PACK_TYPE"C0402"
VOLTAGE"10V"
VALUE"2.2UF"
TOLERANCE"10%"
LOCATION"PC441"
CDS_LIB"pure_quanta"
LOCATION"PC441"
$SEC"1"
CDS_SEC"1";
"B"
$PN"2"13;
"A"
$PN"1"39;
%"Q_RES"
"2","(-8500,9275)","0","pure_quanta","I11";
;
PART_NUMBER"CS-2202FB01"
PACK_TYPE"0402LF"
VALUE"2.2"
MATERIAL"CHIP"
TOLERANCE"1%"
WATTAGE"1/16W"
LOCATION"PR255"
CDS_LIB"pure_quanta"
LOCATION"PR255"
$SEC"1"
CDS_SEC"1";
"A"
$PN"1"1;
"B"
$PN"2"39;
%"UNIVERSAL_GND"
"1","(-7975,9100)","0","logical_power","I12";
;
HDL_POWER"GND"
CDS_LIB"logical_power";
"A"14;
%"Q_CAP"
"1","(-7975,9300)","0","pure_quanta","I13";
;
PART_NUMBER"CH5222KEB01"
PACK_TYPE"C0402"
MATERIAL"X6S"
TOLERANCE"10%"
VOLTAGE"10V"
VALUE"2.2UF"
LOCATION"PC2949"
CDS_LIB"pure_quanta"
$SEC"1"
CDS_SEC"1";
"B"
$PN"2"14;
"A"
$PN"1"1;
%"VCC15"
"1","(-8500,9725)","0","logical_power","I14";
;
HDL_POWER"PVCCFA_EHV_CPU1_PVCC"
CDS_LIB"logical_power";
"A"1;
%"UNIVERSAL_GND"
"1","(-9000,10425)","0","logical_power","I15";
;
HDL_POWER"GND"
CDS_LIB"logical_power";
"A"15;
%"Q_RES"
"2","(-9000,10650)","2","pure_quanta","I16";
;
PART_NUMBER"CS28872FB01"
VALUE"8.87K"
TOLERANCE"1%"
MATERIAL"EMPTY"
WATTAGE"1/16W"
PACK_TYPE"0402LF"
LOCATION"PR1726"
CDS_LIB"pure_quanta"
$SEC"1"
CDS_SEC"1";
"A"
$PN"1"49;
"B"
$PN"2"15;
%"UNIVERSAL_GND"
"1","(-9150,10950)","0","logical_power","I17";
;
HDL_POWER"GND"
CDS_LIB"logical_power";
"A"16;
%"UNIVERSAL_GND"
"1","(-9150,8150)","0","logical_power","I2";
;
HDL_POWER"GND"
CDS_LIB"logical_power";
"A"12;
%"Q_CAP"
"2","(-8325,11050)","0","pure_quanta","I20";
;
PART_NUMBER"CH4104K1B00"
PACK_TYPE"0402"
TOLERANCE"10%"
MATERIAL"X7R"
VOLTAGE"25V"
VALUE"0.1UF"
LOCATION"PC1364"
CDS_LIB"pure_quanta"
$SEC"1"
CDS_SEC"1";
"A"
$PN"1"16;
"B"
$PN"2"43;
%"UNIVERSAL_GND"
"1","(-8500,11425)","0","logical_power","I23";
;
HDL_POWER"GND"
CDS_LIB"logical_power";
"A"17;
%"Q_CAP"
"1","(-8500,11675)","0","pure_quanta","I24";
;
PART_NUMBER"CH5222KEB01"
PACK_TYPE"C0402"
TOLERANCE"10%"
VALUE"2.2UF"
VOLTAGE"10V"
MATERIAL"X6S"
LOCATION"PC440"
CDS_LIB"pure_quanta"
LOCATION"PC440"
$SEC"1"
CDS_SEC"1";
"B"
$PN"2"17;
"A"
$PN"1"37;
%"Q_RES"
"2","(-8500,12075)","0","pure_quanta","I25";
;
PART_NUMBER"CS-2202FB01"
WATTAGE"1/16W"
MATERIAL"CHIP"
TOLERANCE"1%"
PACK_TYPE"0402LF"
VALUE"2.2"
LOCATION"PR254"
CDS_LIB"pure_quanta"
LOCATION"PR254"
$SEC"1"
CDS_SEC"1";
"A"
$PN"1"2;
"B"
$PN"2"37;
%"Q_CAP"
"1","(-7925,12050)","0","pure_quanta","I26";
;
PART_NUMBER"CH5222KEB01"
VOLTAGE"10V"
VALUE"2.2UF"
PACK_TYPE"C0402"
TOLERANCE"10%"
MATERIAL"X6S"
LOCATION"PC2950"
CDS_LIB"pure_quanta"
$SEC"1"
CDS_SEC"1";
"B"
$PN"2"18;
"A"
$PN"1"2;
%"UNIVERSAL_GND"
"1","(-7925,11875)","0","logical_power","I27";
;
HDL_POWER"GND"
CDS_LIB"logical_power";
"A"18;
%"VCC15"
"1","(-8500,12475)","0","logical_power","I28";
;
HDL_POWER"PVCCFA_EHV_CPU1_PVCC"
CDS_LIB"logical_power";
"A"2;
%"ISL99390FRZTR5935"
"1","(-6975,8425)","0","pure_quanta","I29";
;
PART_NUMBER"AL099390004"
MATERIAL"IC"
PART_TYPE"SMLF"
VALUE"ISL99390FRZ-TR5935"
LOCATION"PU51_P1_2"
CDS_LMAN_SYM_OUTLINE"-300,700,250,-650"
NEEDS_NO_SIZE"TRUE"
CDS_LIB"pure_quanta"
$SEC"1"
CDS_SEC"1";
"PGND2"
$PN"7_9-20_24"19;
"GL2"
$PN"41"0;
"GL1"
$PN"6"0;
"DNC"
$PN"31"0;
"EN"
$PN"35"39;
"PGND3"
$PN"40"19;
"VOS"
$PN"1"40;
"VIN2"
$PN"30"3;
"PGND1"
$PN"5"19;
"SW"
$PN"10_19"33;
"LSET"
$PN"37"50;
"IOUT"
$PN"38"46;
"TOUT_FLT"
$PN"36"48;
"PVCC"
$PN"4"1;
"PHASE"
$PN"32"34;
"VIN1"
$PN"25_29"3;
"BOOT"
$PN"33"38;
"AGND"
$PN"2"19;
"VCC"
$PN"3"39;
"REFIN"
$PN"39"47;
"PWM"
$PN"34"41;
%"Q_RES"
"2","(-9000,7850)","2","pure_quanta","I3";
;
PART_NUMBER"CS28872FB01"
PACK_TYPE"0402LF"
VALUE"8.87K"
TOLERANCE"1%"
MATERIAL"EMPTY"
WATTAGE"1/16W"
LOCATION"PR1727"
CDS_LIB"pure_quanta"
$SEC"1"
CDS_SEC"1";
"A"
$PN"1"50;
"B"
$PN"2"11;
%"UNIVERSAL_GND"
"1","(-6325,7700)","0","logical_power","I30";
;
HDL_POWER"GND"
CDS_LIB"logical_power";
"A"19;
%"Q_RES"
"1","(-5275,8175)","0","pure_quanta","I31";
;
PART_NUMBER"CS00002JB13"
MATERIAL"CHIP"
WATTAGE"1/16W"
PACK_TYPE"0402LF"
TOLERANCE"5%"
VALUE"0"
LOCATION"PR1797"
CDS_LIB"pure_quanta"
$SEC"1"
CDS_SEC"1";
"B"
$PN"2"5;
"A"
$PN"1"40;
%"Q_CAP"
"1","(-3700,8225)","0","pure_quanta","I32";
;
PART_NUMBER"CH622KMEA03"
TOLERANCE"20%"
PACK_TYPE"C0805"
MATERIAL"X6S"
VALUE"22UF"
VOLTAGE"4V"
LOCATION"PC456_P1_2"
CDS_LIB"pure_quanta"
LOCATION"PC456_P1_2"
$SEC"1"
CDS_SEC"1";
"B"
$PN"2"20;
"A"
$PN"1"5;
%"Q_CAP"
"1","(-3275,8225)","0","pure_quanta","I33";
;
PART_NUMBER"CH622KMEA03"
TOLERANCE"20%"
PACK_TYPE"C0805"
MATERIAL"X6S"
VOLTAGE"4V"
VALUE"22UF"
LOCATION"PC458_P1_2"
CDS_LIB"pure_quanta"
LOCATION"PC458_P1_2"
$SEC"1"
CDS_SEC"1";
"B"
$PN"2"20;
"A"
$PN"1"5;
%"Q_RES"
"2","(-2800,8225)","0","pure_quanta","I34";
;
PART_NUMBER"CS14992FB06"
VALUE"499"
TOLERANCE"1%"
MATERIAL"CHIP"
PACK_TYPE"0402LF"
WATTAGE"1/16W"
LOCATION"PR4247"
BOM_COST"VR_PCH"
CDS_LIB"pure_quanta"
$SEC"1"
CDS_SEC"1";
"A"
$PN"1"5;
"B"
$PN"2"20;
%"UNIVERSAL_GND"
"1","(-2425,7850)","0","logical_power","I35";
;
HDL_POWER"GND"
CDS_LIB"logical_power";
"A"20;
%"Q_CAP"
"1","(-6175,9325)","0","pure_quanta","I36";
;
PART_NUMBER"TMP_QCH2336K1B12"
TOLERANCE"10%"
MATERIAL"X7R"
PACK_TYPE"0402"
VALUE"3300PF"
VOLTAGE"50V"
LOCATION"PC443_P1_2"
CDS_LIB"pure_quanta"
LOCATION"PC443_P1_2"
$SEC"1"
CDS_SEC"1";
"B"
$PN"2"22;
"A"
$PN"1"3;
%"Q_CAP"
"1","(-5775,9325)","0","pure_quanta","I37";
;
PART_NUMBER"CH5103KEB01"
PACK_TYPE"C0402"
VALUE"1UF"
MATERIAL"X6S"
TOLERANCE"10%"
VOLTAGE"16V"
LOCATION"PC445_P1_2"
CDS_LIB"pure_quanta"
LOCATION"PC445_P1_2"
$SEC"1"
CDS_SEC"1";
"B"
$PN"2"22;
"A"
$PN"1"3;
%"ISL99390FRZTR5935"
"1","(-6975,11225)","0","pure_quanta","I38";
;
PART_NUMBER"AL099390004"
VALUE"ISL99390FRZ-TR5935"
PART_TYPE"SMLF"
MATERIAL"IC"
LOCATION"PU50_P1_1"
SEC_TYPE""
CDS_LIB"pure_quanta"
CDS_LMAN_SYM_OUTLINE"-300,700,250,-650"
NEEDS_NO_SIZE"TRUE"
SEC"1";
"PGND2"
$PN"7_9-20_24"21;
"GL2"
$PN"41"0;
"GL1"
$PN"6"0;
"DNC"
$PN"31"0;
"EN"
$PN"35"37;
"PGND3"
$PN"40"21;
"VOS"
$PN"1"32;
"VIN2"
$PN"30"4;
"PGND1"
$PN"5"21;
"SW"
$PN"10_19"31;
"LSET"
$PN"37"49;
"IOUT"
$PN"38"42;
"TOUT_FLT"
$PN"36"44;
"PVCC"
$PN"4"2;
"PHASE"
$PN"32"35;
"VIN1"
$PN"25_29"4;
"BOOT"
$PN"33"36;
"AGND"
$PN"2"21;
"VCC"
$PN"3"37;
"REFIN"
$PN"39"43;
"PWM"
$PN"34"45;
%"UNIVERSAL_GND"
"1","(-6325,10500)","0","logical_power","I39";
;
HDL_POWER"GND"
CDS_LIB"logical_power";
"A"21;
%"Q_CAP"
"1","(-6175,12125)","0","pure_quanta","I40";
;
PART_NUMBER"TMP_QCH2336K1B12"
PACK_TYPE"0402"
VOLTAGE"50V"
VALUE"3300PF"
TOLERANCE"10%"
MATERIAL"X7R"
LOCATION"PC442_P1_1"
CDS_LIB"pure_quanta"
LOCATION"PC442_P1_1"
$SEC"1"
CDS_SEC"1";
"B"
$PN"2"23;
"A"
$PN"1"4;
%"Q_CAP"
"1","(-5775,12125)","0","pure_quanta","I41";
;
PART_NUMBER"CH5103KEB01"
PACK_TYPE"C0402"
VOLTAGE"16V"
VALUE"1UF"
TOLERANCE"10%"
MATERIAL"X6S"
LOCATION"PC444_P1_1"
CDS_LIB"pure_quanta"
LOCATION"PC444_P1_1"
$SEC"1"
CDS_SEC"1";
"B"
$PN"2"23;
"A"
$PN"1"4;
%"Q_RES"
"1","(-5625,8875)","0","pure_quanta","I42";
;
PART_NUMBER"CS-3302FB01"
PACK_TYPE"0402LF"
MATERIAL"CHIP"
WATTAGE"1/16W"
TOLERANCE"1%"
VALUE"3.3"
LOCATION"PR1795"
CDS_LIB"pure_quanta"
$SEC"1"
CDS_SEC"1";
"B"
$PN"2"30;
"A"
$PN"1"38;
%"Q_CAP"
"1","(-5375,9325)","0","pure_quanta","I43";
;
PART_NUMBER"CH6223MEA01"
TOLERANCE"20%"
PACK_TYPE"C0805"
VALUE"22UF"
VOLTAGE"16V"
MATERIAL"X6S"
LOCATION"PC449_P1_2"
CDS_LIB"pure_quanta"
LOCATION"PC449_P1_2"
$SEC"1"
CDS_SEC"1";
"B"
$PN"2"22;
"A"
$PN"1"3;
%"Q_CAP"
"1","(-4800,8700)","2","pure_quanta","I44";
;
PART_NUMBER"CH4106K1B01"
PACK_TYPE"C0402"
VOLTAGE"50V"
VALUE"100NF"
TOLERANCE"10%"
MATERIAL"X7R"
LOCATION"PC447"
CDS_LIB"pure_quanta"
$SEC"1"
CDS_SEC"1";
"B"
$PN"2"34;
"A"
$PN"1"30;
%"Q_CAP"
"1","(-4975,9325)","0","pure_quanta","I45";
;
PART_NUMBER"CH6223MEA01"
TOLERANCE"20%"
VALUE"22UF"
PACK_TYPE"C0805"
MATERIAL"X6S"
VOLTAGE"16V"
LOCATION"PC451_P1_2"
CDS_LIB"pure_quanta"
LOCATION"PC451_P1_2"
$SEC"1"
CDS_SEC"1";
"B"
$PN"2"22;
"A"
$PN"1"3;
%"Q_INDUCTOR"
"1","(-4575,8450)","0","pure_quanta","I46";
;
PART_NUMBER"CV+12^0EZ03"
MATERIAL"IND"
VALUE"120NH/69A"
PACK_TYPE"SMLF"
LOCATION"PL22"
NEEDS_NO_SIZE"TRUE"
CDS_LIB"pure_quanta"
$SEC"1"
CDS_SEC"1";
"1"
$PN"1"33;
"2"
$PN"2"5;
%"UNIVERSAL_GND"
"1","(-4375,8900)","0","logical_power","I47";
;
HDL_POWER"GND"
CDS_LIB"logical_power";
"A"22;
%"VCC15"
"1","(-4375,9700)","0","logical_power","I48";
;
HDL_POWER"SW_P12V_PVCCINFAON_CPU1_FLT"
CDS_LIB"logical_power";
"A"3;
%"Q_RES"
"1","(-5250,10975)","0","pure_quanta","I49";
;
PART_NUMBER"CS00002JB13"
TOLERANCE"5%"
VALUE"0"
MATERIAL"CHIP"
WATTAGE"1/16W"
PACK_TYPE"0402LF"
LOCATION"PR1796"
CDS_LIB"pure_quanta"
$SEC"1"
CDS_SEC"1";
"B"
$PN"2"6;
"A"
$PN"1"32;
%"Q_RES"
"1","(-5625,11675)","0","pure_quanta","I50";
;
PART_NUMBER"CS-3302FB01"
VALUE"3.3"
WATTAGE"1/16W"
TOLERANCE"1%"
PACK_TYPE"0402LF"
MATERIAL"CHIP"
LOCATION"PR1794"
CDS_LIB"pure_quanta"
$SEC"1"
CDS_SEC"1";
"B"
$PN"2"29;
"A"
$PN"1"36;
%"Q_CAP"
"1","(-5375,12125)","0","pure_quanta","I51";
;
PART_NUMBER"CH6223MEA01"
TOLERANCE"20%"
PACK_TYPE"C0805"
VOLTAGE"16V"
VALUE"22UF"
MATERIAL"X6S"
LOCATION"PC448_P1_1"
CDS_LIB"pure_quanta"
LOCATION"PC448_P1_1"
$SEC"1"
CDS_SEC"1";
"B"
$PN"2"23;
"A"
$PN"1"4;
%"Q_CAP"
"1","(-4800,11500)","2","pure_quanta","I52";
;
PART_NUMBER"CH4106K1B01"
VOLTAGE"50V"
PACK_TYPE"C0402"
VALUE"100NF"
TOLERANCE"10%"
MATERIAL"X7R"
LOCATION"PC446"
CDS_LIB"pure_quanta"
$SEC"1"
CDS_SEC"1";
"B"
$PN"2"35;
"A"
$PN"1"29;
%"Q_CAP"
"1","(-4975,12125)","0","pure_quanta","I53";
;
PART_NUMBER"CH6223MEA01"
TOLERANCE"20%"
PACK_TYPE"C0805"
VALUE"22UF"
VOLTAGE"16V"
MATERIAL"X6S"
LOCATION"PC450_P1_1"
CDS_LIB"pure_quanta"
LOCATION"PC450_P1_1"
$SEC"1"
CDS_SEC"1";
"B"
$PN"2"23;
"A"
$PN"1"4;
%"Q_INDUCTOR"
"1","(-4575,11250)","0","pure_quanta","I54";
;
PART_NUMBER"CV+12^0EZ03"
MATERIAL"IND"
PACK_TYPE"SMLF"
VALUE"120NH/69A"
LOCATION"PL21"
NEEDS_NO_SIZE"TRUE"
CDS_LIB"pure_quanta"
$SEC"1"
CDS_SEC"1";
"1"
$PN"1"31;
"2"
$PN"2"6;
%"Q_CAP"
"1","(-3925,11025)","0","pure_quanta","I55";
;
PART_NUMBER"CH4106K1B01"
PACK_TYPE"C0402"
VALUE"100NF"
VOLTAGE"50V"
TOLERANCE"10%"
MATERIAL"X7R"
LOCATION"PC452_P1_1"
CDS_LIB"pure_quanta"
LOCATION"PC452_P1_1"
$SEC"1"
CDS_SEC"1";
"B"
$PN"2"24;
"A"
$PN"1"6;
%"UNIVERSAL_GND"
"1","(-4375,11700)","0","logical_power","I56";
;
HDL_POWER"GND"
CDS_LIB"logical_power";
"A"23;
%"VCC15"
"1","(-4375,12500)","0","logical_power","I57";
;
HDL_POWER"SW_P12V_PVCCINFAON_CPU1_FLT"
CDS_LIB"logical_power";
"A"4;
%"VCC15"
"1","(-2425,8575)","0","logical_power","I58";
;
HDL_POWER"PVCCINFAON_CPU1"
CDS_LIB"logical_power";
"A"5;
%"Q_CAPP"
"1","(-2475,9225)","0","pure_quanta","I59";
;
PART_NUMBER"CC7560JMD16"
PACK_TYPE"THLF"
VALUE"560UF"
TOLERANCE"20%"
MATERIAL"OSCON"
VOLTAGE"2.5V"
LOCATION"PC1593"
CDS_LIB"pure_quanta"
$SEC"1"
CDS_SEC"1";
"A"
$PN"1"7;
"B"
$PN"2"26;
%"Q_CAP"
"2","(-8325,8250)","0","pure_quanta","I6";
;
PART_NUMBER"CH4104K1B00"
TOLERANCE"10%"
VALUE"0.1UF"
MATERIAL"X7R"
PACK_TYPE"0402"
VOLTAGE"25V"
LOCATION"PC1365"
CDS_LIB"pure_quanta"
$SEC"1"
CDS_SEC"1";
"A"
$PN"1"12;
"B"
$PN"2"47;
%"Q_CAPP"
"1","(-1900,9225)","0","pure_quanta","I60";
;
PART_NUMBER"CC7560JMD16"
PACK_TYPE"THLF"
VALUE"560UF"
TOLERANCE"20%"
MATERIAL"OSCON"
VOLTAGE"2.5V"
LOCATION"PC1595"
CDS_LIB"pure_quanta"
$SEC"1"
CDS_SEC"1";
"A"
$PN"1"7;
"B"
$PN"2"26;
%"Q_CAPP"
"1","(-2475,10150)","0","pure_quanta","I61";
;
PART_NUMBER"CH733RY8807"
PACK_TYPE"SMLF"
MATERIAL"SPCAP"
VOLTAGE"2V"
TOLERANCE"35%"
VALUE"330UF"
LOCATION"PC1588"
CDS_LIB"pure_quanta"
$SEC"1"
CDS_SEC"1";
"A"
$PN"1"8;
"B"
$PN"2"27;
%"Q_CAPP"
"1","(-1900,10150)","0","pure_quanta","I62";
;
PART_NUMBER"CH733RY8807"
PACK_TYPE"SMLF"
VOLTAGE"2V"
VALUE"330UF"
TOLERANCE"35%"
MATERIAL"SPCAP"
LOCATION"PC1594"
CDS_LIB"pure_quanta"
$SEC"1"
CDS_SEC"1";
"A"
$PN"1"8;
"B"
$PN"2"27;
%"Q_CAP"
"1","(-3525,11025)","0","pure_quanta","I63";
;
PART_NUMBER"CH622KMEA03"
TOLERANCE"20%"
PACK_TYPE"C0805"
MATERIAL"X6S"
VALUE"22UF"
VOLTAGE"4V"
LOCATION"PC455_P1_1"
CDS_LIB"pure_quanta"
LOCATION"PC455_P1_1"
$SEC"1"
CDS_SEC"1";
"B"
$PN"2"24;
"A"
$PN"1"6;
%"UNIVERSAL_GND"
"1","(-2800,10650)","0","logical_power","I64";
;
HDL_POWER"GND"
CDS_LIB"logical_power";
"A"24;
%"Q_CAP"
"1","(-3100,11025)","0","pure_quanta","I65";
;
PART_NUMBER"CH622KMEA03"
TOLERANCE"20%"
MATERIAL"X6S"
PACK_TYPE"C0805"
VALUE"22UF"
VOLTAGE"4V"
LOCATION"PC457_P1_1"
CDS_LIB"pure_quanta"
LOCATION"PC457_P1_1"
$SEC"1"
CDS_SEC"1";
"B"
$PN"2"24;
"A"
$PN"1"6;
%"VCC15"
"1","(-2800,11425)","0","logical_power","I66";
;
HDL_POWER"PVCCINFAON_CPU1"
CDS_LIB"logical_power";
"A"6;
%"GND"
"1","(-3125,12100)","0","logical_power","I67";
;
HDL_POWER"GND"
SIZE"1B"
CDS_LIB"logical_power";
"A<SIZE-1..0>\NAC"25;
%"Q_CAP"
"1","(-3125,12350)","0","pure_quanta","I68";
;
PART_NUMBER"CH4106K1B01"
PACK_TYPE"C0402"
MATERIAL"X7R"
TOLERANCE"10%"
VALUE"100NF"
VOLTAGE"50V"
LOCATION"PC1659"
CDS_LIB"pure_quanta"
$SEC"1"
CDS_SEC"1";
"B"
$PN"2"25;
"A"
$PN"1"9;
%"Q_CAPP"
"1","(-2375,12350)","0","pure_quanta","I69";
;
PART_NUMBER"CC72703MD38"
PACK_TYPE"THLF"
TOLERANCE"20%"
MATERIAL"OSCON"
VOLTAGE"16V"
VALUE"270UF"
LOCATION"PC460"
CDS_LIB"pure_quanta"
LOCATION"PC460"
$SEC"1"
CDS_SEC"1";
"A"
$PN"1"10;
"B"
$PN"2"28;
%"Q_CAPP"
"1","(-1975,12350)","0","pure_quanta","I70";
;
PART_NUMBER"CC72703MD38"
PACK_TYPE"THLF"
TOLERANCE"20%"
MATERIAL"OSCON"
VOLTAGE"16V"
VALUE"270UF"
LOCATION"PC461"
CDS_LIB"pure_quanta"
LOCATION"PC461"
$SEC"1"
CDS_SEC"1";
"A"
$PN"1"10;
"B"
$PN"2"28;
%"Q_CAPP"
"1","(-1325,9225)","0","pure_quanta","I71";
;
PART_NUMBER"CC7560JMD16"
PACK_TYPE"THLF"
VALUE"560UF"
TOLERANCE"20%"
MATERIAL"OSCON"
VOLTAGE"2.5V"
LOCATION"PC1596"
CDS_LIB"pure_quanta"
$SEC"1"
CDS_SEC"1";
"A"
$PN"1"7;
"B"
$PN"2"26;
%"UNIVERSAL_GND"
"1","(-725,8900)","0","logical_power","I72";
;
HDL_POWER"GND"
CDS_LIB"logical_power";
"A"26;
%"VCC15"
"1","(-725,9550)","0","logical_power","I73";
;
HDL_POWER"PVCCINFAON_CPU1"
CDS_LIB"logical_power";
"A"7;
%"UNIVERSAL_GND"
"1","(-725,9825)","0","logical_power","I74";
;
HDL_POWER"GND"
CDS_LIB"logical_power";
"A"27;
%"VCC15"
"1","(-725,10475)","0","logical_power","I75";
;
HDL_POWER"PVCCINFAON_CPU1"
CDS_LIB"logical_power";
"A"8;
%"UNIVERSAL_GND"
"1","(-775,12025)","0","logical_power","I76";
;
HDL_POWER"GND"
CDS_LIB"logical_power";
"A"28;
%"VCC15"
"1","(-3125,12725)","0","logical_power","I77";
;
HDL_POWER"P12V_AUX"
CDS_LIB"logical_power";
"A"9;
%"Q_INDUCTOR"
"1","(-2700,12575)","0","pure_quanta","I78";
;
PART_NUMBER"CV+10G0MZ04"
PACK_TYPE"SMLF"
VALUE"100NH/16A"
MATERIAL"IND"
LOCATION"PL23"
NEEDS_NO_SIZE"TRUE"
CDS_LIB"pure_quanta"
LOCATION"PL23"
$SEC"1"
CDS_SEC"1";
"1"
$PN"1"9;
"2"
$PN"2"10;
%"VCC15"
"1","(-775,12675)","0","logical_power","I79";
;
HDL_POWER"SW_P12V_PVCCINFAON_CPU1_FLT"
CDS_LIB"logical_power";
"A"10;
%"UNIVERSAL_GND"
"1","(-8500,8625)","0","logical_power","I9";
;
HDL_POWER"GND"
CDS_LIB"logical_power";
"A"13;
END.
